(kicad_pcb
	(version 20241229)
	(generator "pcbnew")
	(generator_version "9.0")
	(general
		(thickness 1.61)
		(legacy_teardrops no)
	)
	(paper "A3")
	(title_block
		(title "RDIMM DDR5 Tester")
		(date "2026-05-21")
		(rev "2.2.0")
		(company "Antmicro")
		(comment 9 "footprints 523-527 of 796")
	)
	(layers
		(0 "F.Cu" signal)
		(4 "In1.Cu" power)
		(6 "In2.Cu" mixed)
		(8 "In3.Cu" power)
		(10 "In4.Cu" mixed)
		(12 "In5.Cu" power)
		(14 "In6.Cu" mixed)
		(16 "In7.Cu" power)
		(18 "In8.Cu" power)
		(20 "In9.Cu" mixed)
		(22 "In10.Cu" power)
		(2 "B.Cu" signal)
		(9 "F.Adhes" user "F.Adhesive")
		(11 "B.Adhes" user "B.Adhesive")
		(13 "F.Paste" user)
		(15 "B.Paste" user)
		(5 "F.SilkS" user "F.Silkscreen")
		(7 "B.SilkS" user "B.Silkscreen")
		(1 "F.Mask" user)
		(3 "B.Mask" user)
		(17 "Dwgs.User" user "User.Drawings")
		(19 "Cmts.User" user "User.Comments")
		(21 "Eco1.User" user "User.Eco1")
		(23 "Eco2.User" user "User.Eco2")
		(25 "Edge.Cuts" user)
		(27 "Margin" user)
		(31 "F.CrtYd" user "F.Courtyard")
		(29 "B.CrtYd" user "B.Courtyard")
		(35 "F.Fab" user)
		(33 "B.Fab" user)
	)
	(footprint "antmicro-footprints:C_0402_1005Metric"
		(layer "B.Cu")
		(at 254.174499 134.699 180)
		(descr "Capacitor SMD 0402")
		(tags "capacitor SMD 0402")
		(property "Reference" "C203"
			(at -4.125501 -0.401 0)
			(layer "B.SilkS")
			(effects
				(font
					(size 0.7 0.7)
					(thickness 0.15)
				)
				(justify left bottom mirror)
			)
		)
		(property "Value" "C_100n_0402"
			(at -1.022927 -2.155213 0)
			(layer "B.Fab")
			(effects
				(font
					(size 0.7 0.7)
					(thickness 0.15)
				)
				(justify left bottom mirror)
			)
		)
		(property "Datasheet" "https://www.murata.com/products/productdetail?partno=GRM155R61H104KE14%23"
			(at 0 0 180)
			(layer "F.Fab")
			(hide yes)
			(effects
				(font
					(size 1.27 1.27)
					(thickness 0.15)
				)
			)
		)
		(property "Manufacturer" "Murata"
			(at 0 0 180)
			(unlocked yes)
			(layer "B.Fab")
			(hide yes)
			(effects
				(font
					(size 1 1)
					(thickness 0.15)
				)
				(justify mirror)
			)
		)
		(property "MPN" "GRM155R61H104KE14D"
			(at 0 0 180)
			(unlocked yes)
			(layer "B.Fab")
			(hide yes)
			(effects
				(font
					(size 1 1)
					(thickness 0.15)
				)
				(justify mirror)
			)
		)
		(property "Val" "100n"
			(at 0 0 180)
			(unlocked yes)
			(layer "B.Fab")
			(hide yes)
			(effects
				(font
					(size 1 1)
					(thickness 0.15)
				)
				(justify mirror)
			)
		)
		(property "License" "Apache-2.0"
			(at 0 0 180)
			(unlocked yes)
			(layer "B.Fab")
			(hide yes)
			(effects
				(font
					(size 1 1)
					(thickness 0.15)
				)
				(justify mirror)
			)
		)
		(property "Author" "Antmicro"
			(at 0 0 180)
			(unlocked yes)
			(layer "B.Fab")
			(hide yes)
			(effects
				(font
					(size 1 1)
					(thickness 0.15)
				)
				(justify mirror)
			)
		)
		(property "Voltage" "50V"
			(at 0 0 180)
			(unlocked yes)
			(layer "B.Fab")
			(hide yes)
			(effects
				(font
					(size 1 1)
					(thickness 0.15)
				)
				(justify mirror)
			)
		)
		(property "Dielectric" "X5R"
			(at 0 0 180)
			(unlocked yes)
			(layer "B.Fab")
			(hide yes)
			(effects
				(font
					(size 1 1)
					(thickness 0.15)
				)
				(justify mirror)
			)
		)
		(sheetname "/Supply/")
		(sheetfile "supply.kicad_sch")
		(attr smd)
		(fp_rect
			(start -0.925 0.47)
			(end 0.925 -0.47)
			(stroke
				(width 0.05)
				(type default)
			)
			(fill no)
			(layer "B.CrtYd")
		)
		(fp_line
			(start 0.504 0.25)
			(end 0.504 -0.248)
			(stroke
				(width 0.15)
				(type solid)
			)
			(layer "B.Fab")
		)
		(fp_line
			(start 0.504 -0.248)
			(end -0.494 -0.248)
			(stroke
				(width 0.15)
				(type solid)
			)
			(layer "B.Fab")
		)
		(fp_line
			(start -0.494 0.25)
			(end 0.504 0.25)
			(stroke
				(width 0.15)
				(type solid)
			)
			(layer "B.Fab")
		)
		(fp_line
			(start -0.494 -0.248)
			(end -0.494 0.25)
			(stroke
				(width 0.15)
				(type solid)
			)
			(layer "B.Fab")
		)
		(fp_text user "${REFERENCE}"
			(at -0.939 -4.599 0)
			(layer "B.Fab")
			(effects
				(font
					(size 0.7 0.7)
					(thickness 0.15)
				)
				(justify left bottom mirror)
			)
		)
		(fp_text user "Author: Antmicro"
			(at -0.939 -3.399 0)
			(layer "B.Fab")
			(effects
				(font
					(size 0.7 0.7)
					(thickness 0.15)
				)
				(justify left bottom mirror)
			)
		)
		(fp_text user "License: Apache-2.0"
			(at -0.939 -5.799 0)
			(layer "B.Fab")
			(effects
				(font
					(size 0.7 0.7)
					(thickness 0.15)
				)
				(justify left bottom mirror)
			)
		)
		(pad "1" smd roundrect
			(at -0.48 0 180)
			(size 0.59 0.64)
			(layers "B.Cu" "B.Mask" "B.Paste")
			(roundrect_rratio 0.25)
			(net 38 "+3V3_AON")
			(pintype "passive")
		)
		(pad "2" smd roundrect
			(at 0.48 0 180)
			(size 0.59 0.64)
			(layers "B.Cu" "B.Mask" "B.Paste")
			(roundrect_rratio 0.25)
			(net 1 "GND")
			(pintype "passive")
		)
	)
	(footprint "antmicro-footprints:C_0402_1005Metric_EIA"
		(layer "B.Cu")
		(at 190 156.500001 90)
		(descr "Capacitor SMD 0402 (1005 Metric), square (rectangular) end terminal, IPC_7351 nominal, (Body size source: IPC-SM-782 page 76, https://www.pcb-3d.com/wordpress/wp-content/uploads/ipc-sm-782a_amendment_1_and_2.pdf)")
		(tags "capacitor 0402")
		(property "Reference" "C90"
			(at 9.650001 -30.65 90)
			(layer "B.SilkS")
			(effects
				(font
					(size 0.7 0.7)
					(thickness 0.15)
				)
				(justify right bottom mirror)
			)
		)
		(property "Value" "C_1u_25V_0402"
			(at 0 -1.169 90)
			(layer "B.Fab")
			(effects
				(font
					(size 0.7 0.7)
					(thickness 0.15)
				)
				(justify right bottom mirror)
			)
		)
		(property "Datasheet" "https://www.murata.com/products/productdetail?partno=GRM155R61E105KE11%23"
			(at 0 0 90)
			(layer "F.Fab")
			(hide yes)
			(effects
				(font
					(size 1.27 1.27)
					(thickness 0.15)
				)
			)
		)
		(property "MPN" "GRM155R61E105KE11J"
			(at 0 0 90)
			(unlocked yes)
			(layer "B.Fab")
			(hide yes)
			(effects
				(font
					(size 1 1)
					(thickness 0.15)
				)
				(justify mirror)
			)
		)
		(property "Manufacturer" "Murata"
			(at 0 0 90)
			(unlocked yes)
			(layer "B.Fab")
			(hide yes)
			(effects
				(font
					(size 1 1)
					(thickness 0.15)
				)
				(justify mirror)
			)
		)
		(property "License" "Apache-2.0"
			(at 0 0 90)
			(unlocked yes)
			(layer "B.Fab")
			(hide yes)
			(effects
				(font
					(size 1 1)
					(thickness 0.15)
				)
				(justify mirror)
			)
		)
		(property "Author" "Antmicro"
			(at 0 0 90)
			(unlocked yes)
			(layer "B.Fab")
			(hide yes)
			(effects
				(font
					(size 1 1)
					(thickness 0.15)
				)
				(justify mirror)
			)
		)
		(property "Val" "1u"
			(at 0 0 90)
			(unlocked yes)
			(layer "B.Fab")
			(hide yes)
			(effects
				(font
					(size 1 1)
					(thickness 0.15)
				)
				(justify mirror)
			)
		)
		(property "Voltage" "25V"
			(at 0 0 90)
			(unlocked yes)
			(layer "B.Fab")
			(hide yes)
			(effects
				(font
					(size 1 1)
					(thickness 0.15)
				)
				(justify mirror)
			)
		)
		(property "Dielectric" "X5R"
			(at 0 0 90)
			(unlocked yes)
			(layer "B.Fab")
			(hide yes)
			(effects
				(font
					(size 1 1)
					(thickness 0.15)
				)
				(justify mirror)
			)
		)
		(sheetname "/FPGA power/")
		(sheetfile "fpga-power.kicad_sch")
		(attr smd)
		(fp_rect
			(start -0.95 0.45)
			(end 0.95 -0.45)
			(stroke
				(width 0.05)
				(type default)
			)
			(fill no)
			(layer "B.CrtYd")
		)
		(fp_line
			(start 0.498 -0.248)
			(end -0.5 -0.248)
			(stroke
				(width 0.15)
				(type solid)
			)
			(layer "B.Fab")
		)
		(fp_line
			(start -0.5 -0.248)
			(end -0.5 0.25)
			(stroke
				(width 0.15)
				(type solid)
			)
			(layer "B.Fab")
		)
		(fp_line
			(start 0.498 0.25)
			(end 0.498 -0.248)
			(stroke
				(width 0.15)
				(type solid)
			)
			(layer "B.Fab")
		)
		(fp_line
			(start -0.5 0.25)
			(end 0.498 0.25)
			(stroke
				(width 0.15)
				(type solid)
			)
			(layer "B.Fab")
		)
		(fp_text user "Author: Antmicro"
			(at -0.9656 -5.569 270)
			(layer "B.Fab")
			(effects
				(font
					(size 0.7 0.7)
					(thickness 0.15)
				)
				(justify left bottom mirror)
			)
		)
		(fp_text user "${REFERENCE}"
			(at -0.9656 -3.169 270)
			(layer "B.Fab")
			(effects
				(font
					(size 0.7 0.7)
					(thickness 0.15)
				)
				(justify left bottom mirror)
			)
		)
		(fp_text user "License: Apache-2.0"
			(at -0.9656 -4.369 270)
			(layer "B.Fab")
			(effects
				(font
					(size 0.7 0.7)
					(thickness 0.15)
				)
				(justify left bottom mirror)
			)
		)
		(pad "1" smd roundrect
			(at -0.5 0)
			(size 0.6 0.6)
			(layers "B.Cu" "B.Mask" "B.Paste")
			(roundrect_rratio 0.25)
			(net 1 "GND")
			(pintype "passive")
		)
		(pad "2" smd roundrect
			(at 0.498 0 90)
			(size 0.6 0.6)
			(layers "B.Cu" "B.Mask" "B.Paste")
			(roundrect_rratio 0.25)
			(net 553 "+0V85")
			(pintype "passive")
		)
	)
	(footprint "antmicro-footprints:R_0402_1005Metric"
		(layer "B.Cu")
		(at 221.9 177.915 -90)
		(descr "Resistor SMD 0402")
		(tags "resistor SMD 0402")
		(property "Reference" "R200"
			(at -1.74 0.725 90)
			(layer "B.SilkS")
			(effects
				(font
					(size 0.7 0.7)
					(thickness 0.15)
				)
				(justify left bottom mirror)
			)
		)
		(property "Value" "R_0R_0402"
			(at -1.011843 -1.772047 90)
			(layer "B.Fab")
			(effects
				(font
					(size 0.7 0.7)
					(thickness 0.15)
				)
				(justify left bottom mirror)
			)
		)
		(property "Datasheet" "https://industrial.panasonic.com/cdbs/www-data/pdf/RDA0000/AOA0000C301.pdf"
			(at 0 0 270)
			(layer "F.Fab")
			(hide yes)
			(effects
				(font
					(size 1.27 1.27)
					(thickness 0.15)
				)
			)
		)
		(property "MPN" "ERJ2GE0R00X"
			(at 0 0 270)
			(unlocked yes)
			(layer "B.Fab")
			(hide yes)
			(effects
				(font
					(size 1 1)
					(thickness 0.15)
				)
				(justify mirror)
			)
		)
		(property "Manufacturer" "Panasonic"
			(at 0 0 270)
			(unlocked yes)
			(layer "B.Fab")
			(hide yes)
			(effects
				(font
					(size 1 1)
					(thickness 0.15)
				)
				(justify mirror)
			)
		)
		(property "License" "Apache-2.0"
			(at 0 0 270)
			(unlocked yes)
			(layer "B.Fab")
			(hide yes)
			(effects
				(font
					(size 1 1)
					(thickness 0.15)
				)
				(justify mirror)
			)
		)
		(property "Author" "Antmicro"
			(at 0 0 270)
			(unlocked yes)
			(layer "B.Fab")
			(hide yes)
			(effects
				(font
					(size 1 1)
					(thickness 0.15)
				)
				(justify mirror)
			)
		)
		(property "Val" "0R"
			(at 0 0 270)
			(unlocked yes)
			(layer "B.Fab")
			(hide yes)
			(effects
				(font
					(size 1 1)
					(thickness 0.15)
				)
				(justify mirror)
			)
		)
		(property "Tolerance" "~"
			(at 0 0 270)
			(unlocked yes)
			(layer "B.Fab")
			(hide yes)
			(effects
				(font
					(size 1 1)
					(thickness 0.15)
				)
				(justify mirror)
			)
		)
		(property "Current" "1A"
			(at 0 0 270)
			(unlocked yes)
			(layer "B.Fab")
			(hide yes)
			(effects
				(font
					(size 1 1)
					(thickness 0.15)
				)
				(justify mirror)
			)
		)
		(sheetname "/Supply/DC-DC VCCINT/")
		(sheetfile "dc-dc-vccint.kicad_sch")
		(attr smd)
		(fp_rect
			(start -0.925 0.47)
			(end 0.925 -0.47)
			(stroke
				(width 0.05)
				(type default)
			)
			(fill no)
			(layer "B.CrtYd")
		)
		(fp_rect
			(start -0.5 0.25)
			(end 0.5 -0.25)
			(stroke
				(width 0.15)
				(type solid)
			)
			(fill no)
			(layer "B.Fab")
		)
		(fp_text user "License: Apache-2.0"
			(at -0.95 -5.169 90)
			(layer "B.Fab")
			(effects
				(font
					(size 0.7 0.7)
					(thickness 0.15)
				)
				(justify left bottom mirror)
			)
		)
		(fp_text user "${REFERENCE}"
			(at -0.95 -3.168 90)
			(layer "B.Fab")
			(effects
				(font
					(size 0.7 0.7)
					(thickness 0.15)
				)
				(justify left bottom mirror)
			)
		)
		(fp_text user "Author: Antmicro"
			(at -0.95 -4.169 90)
			(layer "B.Fab")
			(effects
				(font
					(size 0.7 0.7)
					(thickness 0.15)
				)
				(justify left bottom mirror)
			)
		)
		(pad "1" smd roundrect
			(at -0.48 0 270)
			(size 0.59 0.64)
			(layers "B.Cu" "B.Mask" "B.Paste")
			(roundrect_rratio 0.25)
			(net 754 "/Supply/DC-DC VCCINT/VREF+")
			(pintype "passive")
		)
		(pad "2" smd roundrect
			(at 0.48 0 270)
			(size 0.59 0.64)
			(layers "B.Cu" "B.Mask" "B.Paste")
			(roundrect_rratio 0.25)
			(net 756 "Net-(C264-Pad2)")
			(pintype "passive")
		)
	)
	(footprint "antmicro-footprints:C_0603_1608Metric"
		(layer "B.Cu")
		(at 216.91 172.06 90)
		(descr "Capacitor SMD 0603")
		(tags "capacitor 0603")
		(property "Reference" "C269"
			(at -4.04 0.39 90)
			(layer "B.SilkS")
			(effects
				(font
					(size 0.7 0.7)
					(thickness 0.15)
				)
				(justify right bottom mirror)
			)
		)
		(property "Value" "C_22u_0603"
			(at -1.42757 -1.770288 90)
			(layer "B.Fab")
			(effects
				(font
					(size 0.7 0.7)
					(thickness 0.15)
				)
				(justify right bottom mirror)
			)
		)
		(property "Datasheet" "https://www.murata.com/products/productdetail?partno=GRM188R60J226MEA0%23"
			(at 0 0 90)
			(layer "F.Fab")
			(hide yes)
			(effects
				(font
					(size 1.27 1.27)
					(thickness 0.15)
				)
			)
		)
		(property "Manufacturer" "Murata"
			(at 0 0 90)
			(unlocked yes)
			(layer "B.Fab")
			(hide yes)
			(effects
				(font
					(size 1 1)
					(thickness 0.15)
				)
				(justify mirror)
			)
		)
		(property "MPN" "GRM188R60J226MEA0D"
			(at 0 0 90)
			(unlocked yes)
			(layer "B.Fab")
			(hide yes)
			(effects
				(font
					(size 1 1)
					(thickness 0.15)
				)
				(justify mirror)
			)
		)
		(property "Val" "22u"
			(at 0 0 90)
			(unlocked yes)
			(layer "B.Fab")
			(hide yes)
			(effects
				(font
					(size 1 1)
					(thickness 0.15)
				)
				(justify mirror)
			)
		)
		(property "License" "Apache-2.0"
			(at 0 0 90)
			(unlocked yes)
			(layer "B.Fab")
			(hide yes)
			(effects
				(font
					(size 1 1)
					(thickness 0.15)
				)
				(justify mirror)
			)
		)
		(property "Author" "Antmicro"
			(at 0 0 90)
			(unlocked yes)
			(layer "B.Fab")
			(hide yes)
			(effects
				(font
					(size 1 1)
					(thickness 0.15)
				)
				(justify mirror)
			)
		)
		(property "Voltage" ""
			(at 0 0 90)
			(unlocked yes)
			(layer "B.Fab")
			(hide yes)
			(effects
				(font
					(size 1 1)
					(thickness 0.15)
				)
				(justify mirror)
			)
		)
		(property "Dielectric" ""
			(at 0 0 90)
			(unlocked yes)
			(layer "B.Fab")
			(hide yes)
			(effects
				(font
					(size 1 1)
					(thickness 0.15)
				)
				(justify mirror)
			)
		)
		(sheetname "/Supply/DC-DC VCCINT/")
		(sheetfile "dc-dc-vccint.kicad_sch")
		(attr smd)
		(fp_line
			(start -0.15 -0.4)
			(end 0.15 -0.4)
			(stroke
				(width 0.15)
				(type solid)
			)
			(layer "B.SilkS")
		)
		(fp_line
			(start -0.15 0.4)
			(end 0.15 0.4)
			(stroke
				(width 0.15)
				(type solid)
			)
			(layer "B.SilkS")
		)
		(fp_rect
			(start -1.25 0.65)
			(end 1.25 -0.65)
			(stroke
				(width 0.05)
				(type solid)
			)
			(fill no)
			(layer "B.CrtYd")
		)
		(fp_rect
			(start -0.8 0.4)
			(end 0.8 -0.4)
			(stroke
				(width 0.15)
				(type solid)
			)
			(fill no)
			(layer "B.Fab")
		)
		(fp_text user "License: Apache-2.0"
			(at -1.682 -5.895 270)
			(layer "B.Fab")
			(effects
				(font
					(size 0.7 0.7)
					(thickness 0.15)
				)
				(justify left bottom mirror)
			)
		)
		(fp_text user "Author: Antmicro"
			(at -1.682 -4.894 270)
			(layer "B.Fab")
			(effects
				(font
					(size 0.7 0.7)
					(thickness 0.15)
				)
				(justify left bottom mirror)
			)
		)
		(fp_text user "${REFERENCE}"
			(at -1.682 -3.895 270)
			(layer "B.Fab")
			(effects
				(font
					(size 0.7 0.7)
					(thickness 0.15)
				)
				(justify left bottom mirror)
			)
		)
		(pad "1" smd roundrect
			(at -0.7 0 90)
			(size 0.8 1)
			(layers "B.Cu" "B.Mask" "B.Paste")
			(roundrect_rratio 0.2)
			(net 1 "GND")
			(pintype "passive")
		)
		(pad "2" smd roundrect
			(at 0.7 0 90)
			(size 0.8 1)
			(layers "B.Cu" "B.Mask" "B.Paste")
			(roundrect_rratio 0.2)
			(net 223 "/Supply/DC-DC VCCINT/0V85_REG0")
			(pintype "passive")
		)
	)
	(footprint "antmicro-footprints:R_0402_1005Metric"
		(layer "B.Cu")
		(at 225.32 183.755)
		(descr "Resistor SMD 0402")
		(tags "resistor SMD 0402")
		(property "Reference" "R181"
			(at 1.83 0.495 0)
			(layer "B.SilkS")
			(effects
				(font
					(size 0.7 0.7)
					(thickness 0.15)
				)
				(justify right bottom mirror)
			)
		)
		(property "Value" "R_0R_0402"
			(at -1.011843 -1.772047 0)
			(layer "B.Fab")
			(effects
				(font
					(size 0.7 0.7)
					(thickness 0.15)
				)
				(justify right bottom mirror)
			)
		)
		(property "Datasheet" "https://industrial.panasonic.com/cdbs/www-data/pdf/RDA0000/AOA0000C301.pdf"
			(at 0 0 0)
			(layer "F.Fab")
			(hide yes)
			(effects
				(font
					(size 1.27 1.27)
					(thickness 0.15)
				)
			)
		)
		(property "MPN" "ERJ2GE0R00X"
			(at 0 0 0)
			(unlocked yes)
			(layer "B.Fab")
			(hide yes)
			(effects
				(font
					(size 1 1)
					(thickness 0.15)
				)
				(justify mirror)
			)
		)
		(property "Manufacturer" "Panasonic"
			(at 0 0 0)
			(unlocked yes)
			(layer "B.Fab")
			(hide yes)
			(effects
				(font
					(size 1 1)
					(thickness 0.15)
				)
				(justify mirror)
			)
		)
		(property "License" "Apache-2.0"
			(at 0 0 0)
			(unlocked yes)
			(layer "B.Fab")
			(hide yes)
			(effects
				(font
					(size 1 1)
					(thickness 0.15)
				)
				(justify mirror)
			)
		)
		(property "Author" "Antmicro"
			(at 0 0 0)
			(unlocked yes)
			(layer "B.Fab")
			(hide yes)
			(effects
				(font
					(size 1 1)
					(thickness 0.15)
				)
				(justify mirror)
			)
		)
		(property "Val" "0R"
			(at 0 0 0)
			(unlocked yes)
			(layer "B.Fab")
			(hide yes)
			(effects
				(font
					(size 1 1)
					(thickness 0.15)
				)
				(justify mirror)
			)
		)
		(property "Tolerance" "~"
			(at 0 0 0)
			(unlocked yes)
			(layer "B.Fab")
			(hide yes)
			(effects
				(font
					(size 1 1)
					(thickness 0.15)
				)
				(justify mirror)
			)
		)
		(property "Current" "1A"
			(at 0 0 0)
			(unlocked yes)
			(layer "B.Fab")
			(hide yes)
			(effects
				(font
					(size 1 1)
					(thickness 0.15)
				)
				(justify mirror)
			)
		)
		(sheetname "/Supply/DC-DC VCCINT/")
		(sheetfile "dc-dc-vccint.kicad_sch")
		(attr smd)
		(fp_rect
			(start -0.925 0.47)
			(end 0.925 -0.47)
			(stroke
				(width 0.05)
				(type default)
			)
			(fill no)
			(layer "B.CrtYd")
		)
		(fp_rect
			(start -0.5 0.25)
			(end 0.5 -0.25)
			(stroke
				(width 0.15)
				(type solid)
			)
			(fill no)
			(layer "B.Fab")
		)
		(fp_text user "Author: Antmicro"
			(at -0.95 -4.169 180)
			(layer "B.Fab")
			(effects
				(font
					(size 0.7 0.7)
					(thickness 0.15)
				)
				(justify left bottom mirror)
			)
		)
		(fp_text user "License: Apache-2.0"
			(at -0.95 -5.169 180)
			(layer "B.Fab")
			(effects
				(font
					(size 0.7 0.7)
					(thickness 0.15)
				)
				(justify left bottom mirror)
			)
		)
		(fp_text user "${REFERENCE}"
			(at -0.95 -3.168 180)
			(layer "B.Fab")
			(effects
				(font
					(size 0.7 0.7)
					(thickness 0.15)
				)
				(justify left bottom mirror)
			)
		)
		(pad "1" smd roundrect
			(at -0.48 0)
			(size 0.59 0.64)
			(layers "B.Cu" "B.Mask" "B.Paste")
			(roundrect_rratio 0.25)
			(net 721 "/Supply/DC-DC VCCINT/PASS0")
			(pintype "passive")
		)
		(pad "2" smd roundrect
			(at 0.48 0)
			(size 0.59 0.64)
			(layers "B.Cu" "B.Mask" "B.Paste")
			(roundrect_rratio 0.25)
			(net 722 "/Supply/DC-DC VCCINT/TAKE1")
			(pintype "passive")
		)
	)
)
